# S9S_MB_2U (Grand Teton) — schematic netlist excerpt (pin names and nets, part order shuffled) for the footprints in the layout excerpt that follows; sources: Cadence DE-HDL packaged netlist, KiCad conversion of 03242023_DA0F0TMBIJ0_F0T_Motherboard_J_brd_V01_OCP.brd

R4596  Q_RES  1K 1% EMPTY  pkg 0402LF  page 195 : A = FAB_BMC_REV_ID0 ; B = GND
C995  Q_CAP  10UF 6.3V 20% X6S  pkg C0402  page 74 : A = PVCCIN_CPU0 ; B = GND

(kicad_pcb
	(version 20260206)
	(generator "pcbnew")
	(generator_version "10.0")
	(general
		(thickness 1.6)
		(legacy_teardrops no)
	)
	(paper "A4")
	(title_block
		(title "03242023_DA0F0TMBIJ0_F0T_Motherboard_J_brd_V01_OCP.brd")
		(comment 1 "Grand Teton / footprints 3800-3801 of 6105")
	)
	(layers
		(0 "F.Cu" signal "TOP")
		(4 "In1.Cu" signal "GND")
		(6 "In2.Cu" signal "IN1")
		(8 "In3.Cu" signal "GND1")
		(10 "In4.Cu" signal "IN2")
		(12 "In5.Cu" signal "GND2")
		(14 "In6.Cu" signal "IN3")
		(16 "In7.Cu" signal "GND3")
		(18 "In8.Cu" signal "VCC")
		(20 "In9.Cu" signal "VCC1")
		(22 "In10.Cu" signal "GND4")
		(24 "In11.Cu" signal "IN4")
		(26 "In12.Cu" signal "GND5")
		(28 "In13.Cu" signal "IN5")
		(30 "In14.Cu" signal "GND6")
		(32 "In15.Cu" signal "IN6")
		(34 "In16.Cu" signal "GND7")
		(2 "B.Cu" signal "BOTTOM")
		(9 "F.Adhes" user "F.Adhesive")
		(11 "B.Adhes" user "B.Adhesive")
		(13 "F.Paste" user "Package Geometry/Pastemask Top")
		(15 "B.Paste" user "Package Geometry/Pastemask Bottom")
		(5 "F.SilkS" user "Ref Des/Silkscreen Top")
		(7 "B.SilkS" user "Ref Des/Silkscreen Bottom")
		(1 "F.Mask" user "Board Geometry/Soldermask Top")
		(3 "B.Mask" user "Board Geometry/Soldermask Bottom")
		(17 "Dwgs.User" user "User.Drawings")
		(19 "Cmts.User" user "User.Comments")
		(21 "Eco1.User" user "User.Eco1")
		(23 "Eco2.User" user "User.Eco2")
		(25 "Edge.Cuts" user "Board Geometry/Outline")
		(27 "Margin" user)
		(31 "F.CrtYd" user "Package Geometry/Place Bound Top")
		(29 "B.CrtYd" user "Package Geometry/Place Bound Bottom")
		(35 "F.Fab" user "Ref Des/Assembly Top")
		(33 "B.Fab" user "Ref Des/Assembly Bottom")
	)
	(footprint ""
		(layer "F.Cu")
		(at 180.4924 -94.338648 90)
		(property "Reference" "R4596"
			(at 0 0 90)
			(layer "F.SilkS")
			(hide yes)
			(effects
				(font
					(size 1.27 1.27)
				)
			)
		)
		(property "Value" ""
			(at 0 0 90)
			(layer "F.Fab")
			(effects
				(font
					(size 1.27 1.27)
				)
			)
		)
		(duplicate_pad_numbers_are_jumpers no)
		(fp_line
			(start 0.7874 -0.4064)
			(end 0.7874 0.4064)
			(stroke
				(width 0.1524)
				(type default)
			)
			(layer "F.SilkS")
		)
		(fp_line
			(start -0.7874 -0.4064)
			(end 0.7874 -0.4064)
			(stroke
				(width 0.1524)
				(type default)
			)
			(layer "F.SilkS")
		)
		(fp_line
			(start 0.7874 0.4064)
			(end -0.7874 0.4064)
			(stroke
				(width 0.1524)
				(type default)
			)
			(layer "F.SilkS")
		)
		(fp_line
			(start -0.7874 0.4064)
			(end -0.7874 -0.4064)
			(stroke
				(width 0.1524)
				(type default)
			)
			(layer "F.SilkS")
		)
		(fp_line
			(start -0.12065 -0.305054)
			(end -0.12065 -0.2794)
			(stroke
				(width 0.1)
				(type default)
			)
			(layer "F.Fab")
		)
		(fp_line
			(start -0.67945 -0.305054)
			(end -0.12065 -0.305054)
			(stroke
				(width 0.1)
				(type default)
			)
			(layer "F.Fab")
		)
		(fp_line
			(start 0.67945 -0.3048)
			(end 0.67945 0.3048)
			(stroke
				(width 0.1)
				(type default)
			)
			(layer "F.Fab")
		)
		(fp_line
			(start 0.12065 -0.3048)
			(end 0.67945 -0.3048)
			(stroke
				(width 0.1)
				(type default)
			)
			(layer "F.Fab")
		)
		(fp_line
			(start 0.12065 -0.2794)
			(end 0.12065 -0.3048)
			(stroke
				(width 0.1)
				(type default)
			)
			(layer "F.Fab")
		)
		(fp_line
			(start -0.12065 -0.2794)
			(end 0.12065 -0.2794)
			(stroke
				(width 0.1)
				(type default)
			)
			(layer "F.Fab")
		)
		(fp_line
			(start 0.120396 0.2794)
			(end -0.12065 0.2794)
			(stroke
				(width 0.1)
				(type default)
			)
			(layer "F.Fab")
		)
		(fp_line
			(start -0.12065 0.2794)
			(end -0.12065 0.3048)
			(stroke
				(width 0.1)
				(type default)
			)
			(layer "F.Fab")
		)
		(fp_line
			(start 0.67945 0.3048)
			(end 0.120396 0.3048)
			(stroke
				(width 0.1)
				(type default)
			)
			(layer "F.Fab")
		)
		(fp_line
			(start 0.120396 0.3048)
			(end 0.120396 0.2794)
			(stroke
				(width 0.1)
				(type default)
			)
			(layer "F.Fab")
		)
		(fp_line
			(start -0.12065 0.3048)
			(end -0.67945 0.3048)
			(stroke
				(width 0.1)
				(type default)
			)
			(layer "F.Fab")
		)
		(fp_line
			(start -0.67945 0.3048)
			(end -0.67945 -0.305054)
			(stroke
				(width 0.1)
				(type default)
			)
			(layer "F.Fab")
		)
		(pad "1" smd rect
			(at -0.40005 0 270)
			(size 0.4572 0.508)
			(layers "F.Cu" "F.Mask" "F.Paste")
			(net "FAB_BMC_REV_ID0")
		)
		(pad "2" smd rect
			(at 0.40005 0 270)
			(size 0.4572 0.508)
			(layers "F.Cu" "F.Mask" "F.Paste")
			(net "GND")
		)
	)
	(footprint ""
		(layer "F.Cu")
		(at 352.289618 -244.03177 90)
		(property "Reference" "C995"
			(at 0 0 90)
			(layer "F.SilkS")
			(hide yes)
			(effects
				(font
					(size 1.27 1.27)
				)
			)
		)
		(property "Value" ""
			(at 0 0 90)
			(layer "F.Fab")
			(effects
				(font
					(size 1.27 1.27)
				)
			)
		)
		(duplicate_pad_numbers_are_jumpers no)
		(fp_line
			(start 0.7874 -0.4064)
			(end 0.7874 0.4064)
			(stroke
				(width 0.1524)
				(type default)
			)
			(layer "F.SilkS")
		)
		(fp_line
			(start -0.7874 -0.4064)
			(end 0.7874 -0.4064)
			(stroke
				(width 0.1524)
				(type default)
			)
			(layer "F.SilkS")
		)
		(fp_line
			(start 0.7874 0.4064)
			(end -0.7874 0.4064)
			(stroke
				(width 0.1524)
				(type default)
			)
			(layer "F.SilkS")
		)
		(fp_line
			(start -0.7874 0.4064)
			(end -0.7874 -0.4064)
			(stroke
				(width 0.1524)
				(type default)
			)
			(layer "F.SilkS")
		)
		(fp_line
			(start -0.12065 -0.305054)
			(end -0.12065 -0.2794)
			(stroke
				(width 0.1)
				(type default)
			)
			(layer "F.Fab")
		)
		(fp_line
			(start -0.67945 -0.305054)
			(end -0.12065 -0.305054)
			(stroke
				(width 0.1)
				(type default)
			)
			(layer "F.Fab")
		)
		(fp_line
			(start 0.67945 -0.3048)
			(end 0.67945 0.3048)
			(stroke
				(width 0.1)
				(type default)
			)
			(layer "F.Fab")
		)
		(fp_line
			(start 0.12065 -0.3048)
			(end 0.67945 -0.3048)
			(stroke
				(width 0.1)
				(type default)
			)
			(layer "F.Fab")
		)
		(fp_line
			(start 0.12065 -0.2794)
			(end 0.12065 -0.3048)
			(stroke
				(width 0.1)
				(type default)
			)
			(layer "F.Fab")
		)
		(fp_line
			(start -0.12065 -0.2794)
			(end 0.12065 -0.2794)
			(stroke
				(width 0.1)
				(type default)
			)
			(layer "F.Fab")
		)
		(fp_line
			(start 0.120396 0.2794)
			(end -0.12065 0.2794)
			(stroke
				(width 0.1)
				(type default)
			)
			(layer "F.Fab")
		)
		(fp_line
			(start -0.12065 0.2794)
			(end -0.12065 0.3048)
			(stroke
				(width 0.1)
				(type default)
			)
			(layer "F.Fab")
		)
		(fp_line
			(start 0.67945 0.3048)
			(end 0.120396 0.3048)
			(stroke
				(width 0.1)
				(type default)
			)
			(layer "F.Fab")
		)
		(fp_line
			(start 0.120396 0.3048)
			(end 0.120396 0.2794)
			(stroke
				(width 0.1)
				(type default)
			)
			(layer "F.Fab")
		)
		(fp_line
			(start -0.12065 0.3048)
			(end -0.67945 0.3048)
			(stroke
				(width 0.1)
				(type default)
			)
			(layer "F.Fab")
		)
		(fp_line
			(start -0.67945 0.3048)
			(end -0.67945 -0.305054)
			(stroke
				(width 0.1)
				(type default)
			)
			(layer "F.Fab")
		)
		(pad "1" smd circle
			(at -0.40005 0 90)
			(size 0 0)
			(layers "F.Cu" "F.Mask" "F.Paste")
			(net "PVCCIN_CPU0")
		)
		(pad "2" smd circle
			(at 0.40005 0 90)
			(size 0 0)
			(layers "F.Cu" "F.Mask" "F.Paste")
			(net "GND")
		)
	)
)
